(kicad_pcb
	(version 20241229)
	(generator "pcbnew")
	(generator_version "9.0")
	(general
		(thickness 1.61)
		(legacy_teardrops no)
	)
	(paper "A3")
	(title_block
		(title "RDIMM DDR5 Tester")
		(date "2026-05-21")
		(rev "2.2.0")
		(company "Antmicro")
		(comment 9 "footprints 683-687 of 796")
	)
	(layers
		(0 "F.Cu" signal)
		(4 "In1.Cu" power)
		(6 "In2.Cu" mixed)
		(8 "In3.Cu" power)
		(10 "In4.Cu" mixed)
		(12 "In5.Cu" power)
		(14 "In6.Cu" mixed)
		(16 "In7.Cu" power)
		(18 "In8.Cu" power)
		(20 "In9.Cu" mixed)
		(22 "In10.Cu" power)
		(2 "B.Cu" signal)
		(9 "F.Adhes" user "F.Adhesive")
		(11 "B.Adhes" user "B.Adhesive")
		(13 "F.Paste" user)
		(15 "B.Paste" user)
		(5 "F.SilkS" user "F.Silkscreen")
		(7 "B.SilkS" user "B.Silkscreen")
		(1 "F.Mask" user)
		(3 "B.Mask" user)
		(17 "Dwgs.User" user "User.Drawings")
		(19 "Cmts.User" user "User.Comments")
		(21 "Eco1.User" user "User.Eco1")
		(23 "Eco2.User" user "User.Eco2")
		(25 "Edge.Cuts" user)
		(27 "Margin" user)
		(31 "F.CrtYd" user "F.Courtyard")
		(29 "B.CrtYd" user "B.Courtyard")
		(35 "F.Fab" user)
		(33 "B.Fab" user)
	)
	(footprint "antmicro-footprints:C_0402_1005Metric_EIA"
		(layer "B.Cu")
		(at 192 156.5 -90)
		(descr "Capacitor SMD 0402 (1005 Metric), square (rectangular) end terminal, IPC_7351 nominal, (Body size source: IPC-SM-782 page 76, https://www.pcb-3d.com/wordpress/wp-content/uploads/ipc-sm-782a_amendment_1_and_2.pdf)")
		(tags "capacitor 0402")
		(property "Reference" "C48"
			(at -12 30.65 90)
			(layer "B.SilkS")
			(effects
				(font
					(size 0.7 0.7)
					(thickness 0.15)
				)
				(justify left bottom mirror)
			)
		)
		(property "Value" "C_100n_0402"
			(at 0 -1.169 90)
			(layer "B.Fab")
			(effects
				(font
					(size 0.7 0.7)
					(thickness 0.15)
				)
				(justify left bottom mirror)
			)
		)
		(property "Datasheet" "https://www.murata.com/products/productdetail?partno=GRM155R61H104KE14%23"
			(at 0 0 270)
			(layer "F.Fab")
			(hide yes)
			(effects
				(font
					(size 1.27 1.27)
					(thickness 0.15)
				)
			)
		)
		(property "MPN" "GRM155R61H104KE14D"
			(at 0 0 270)
			(unlocked yes)
			(layer "B.Fab")
			(hide yes)
			(effects
				(font
					(size 1 1)
					(thickness 0.15)
				)
				(justify mirror)
			)
		)
		(property "Manufacturer" "Murata"
			(at 0 0 270)
			(unlocked yes)
			(layer "B.Fab")
			(hide yes)
			(effects
				(font
					(size 1 1)
					(thickness 0.15)
				)
				(justify mirror)
			)
		)
		(property "License" "Apache-2.0"
			(at 0 0 270)
			(unlocked yes)
			(layer "B.Fab")
			(hide yes)
			(effects
				(font
					(size 1 1)
					(thickness 0.15)
				)
				(justify mirror)
			)
		)
		(property "Author" "Antmicro"
			(at 0 0 270)
			(unlocked yes)
			(layer "B.Fab")
			(hide yes)
			(effects
				(font
					(size 1 1)
					(thickness 0.15)
				)
				(justify mirror)
			)
		)
		(property "Val" "100n"
			(at 0 0 270)
			(unlocked yes)
			(layer "B.Fab")
			(hide yes)
			(effects
				(font
					(size 1 1)
					(thickness 0.15)
				)
				(justify mirror)
			)
		)
		(property "Voltage" "50V"
			(at 0 0 270)
			(unlocked yes)
			(layer "B.Fab")
			(hide yes)
			(effects
				(font
					(size 1 1)
					(thickness 0.15)
				)
				(justify mirror)
			)
		)
		(property "Dielectric" "X5R"
			(at 0 0 270)
			(unlocked yes)
			(layer "B.Fab")
			(hide yes)
			(effects
				(font
					(size 1 1)
					(thickness 0.15)
				)
				(justify mirror)
			)
		)
		(sheetname "/FPGA power/")
		(sheetfile "fpga-power.kicad_sch")
		(attr smd)
		(fp_rect
			(start -0.95 0.45)
			(end 0.95 -0.45)
			(stroke
				(width 0.05)
				(type default)
			)
			(fill no)
			(layer "B.CrtYd")
		)
		(fp_line
			(start -0.5 0.25)
			(end 0.498 0.25)
			(stroke
				(width 0.15)
				(type solid)
			)
			(layer "B.Fab")
		)
		(fp_line
			(start 0.498 0.25)
			(end 0.498 -0.248)
			(stroke
				(width 0.15)
				(type solid)
			)
			(layer "B.Fab")
		)
		(fp_line
			(start -0.5 -0.248)
			(end -0.5 0.25)
			(stroke
				(width 0.15)
				(type solid)
			)
			(layer "B.Fab")
		)
		(fp_line
			(start 0.498 -0.248)
			(end -0.5 -0.248)
			(stroke
				(width 0.15)
				(type solid)
			)
			(layer "B.Fab")
		)
		(fp_text user "License: Apache-2.0"
			(at -0.9656 -4.369 90)
			(layer "B.Fab")
			(effects
				(font
					(size 0.7 0.7)
					(thickness 0.15)
				)
				(justify left bottom mirror)
			)
		)
		(fp_text user "Author: Antmicro"
			(at -0.9656 -5.569 90)
			(layer "B.Fab")
			(effects
				(font
					(size 0.7 0.7)
					(thickness 0.15)
				)
				(justify left bottom mirror)
			)
		)
		(fp_text user "${REFERENCE}"
			(at -0.9656 -3.169 90)
			(layer "B.Fab")
			(effects
				(font
					(size 0.7 0.7)
					(thickness 0.15)
				)
				(justify left bottom mirror)
			)
		)
		(pad "1" smd roundrect
			(at -0.5 0 180)
			(size 0.6 0.6)
			(layers "B.Cu" "B.Mask" "B.Paste")
			(roundrect_rratio 0.25)
			(net 1 "GND")
			(pintype "passive")
		)
		(pad "2" smd roundrect
			(at 0.498 0 270)
			(size 0.6 0.6)
			(layers "B.Cu" "B.Mask" "B.Paste")
			(roundrect_rratio 0.25)
			(net 553 "+0V85")
			(pintype "passive")
		)
	)
	(footprint "antmicro-footprints:R_0402_1005Metric"
		(layer "B.Cu")
		(at 211.91 153.15 180)
		(descr "Resistor SMD 0402")
		(tags "resistor SMD 0402")
		(property "Reference" "R4"
			(at -2.53 -0.46 0)
			(layer "B.SilkS")
			(effects
				(font
					(size 0.7 0.7)
					(thickness 0.15)
				)
				(justify left bottom mirror)
			)
		)
		(property "Value" "R_4k7_0402"
			(at -1.011843 -1.772047 0)
			(layer "B.Fab")
			(effects
				(font
					(size 0.7 0.7)
					(thickness 0.15)
				)
				(justify left bottom mirror)
			)
		)
		(property "Datasheet" "https://www.bourns.com/docs/product-datasheets/cr.pdf"
			(at 0 0 180)
			(layer "F.Fab")
			(hide yes)
			(effects
				(font
					(size 1.27 1.27)
					(thickness 0.15)
				)
			)
		)
		(property "Manufacturer" "Bourns"
			(at 0 0 180)
			(unlocked yes)
			(layer "B.Fab")
			(hide yes)
			(effects
				(font
					(size 1 1)
					(thickness 0.15)
				)
				(justify mirror)
			)
		)
		(property "MPN" "CR0402-FX-4701GLF"
			(at 0 0 180)
			(unlocked yes)
			(layer "B.Fab")
			(hide yes)
			(effects
				(font
					(size 1 1)
					(thickness 0.15)
				)
				(justify mirror)
			)
		)
		(property "Val" "4k7"
			(at 0 0 180)
			(unlocked yes)
			(layer "B.Fab")
			(hide yes)
			(effects
				(font
					(size 1 1)
					(thickness 0.15)
				)
				(justify mirror)
			)
		)
		(property "License" "Apache-2.0"
			(at 0 0 180)
			(unlocked yes)
			(layer "B.Fab")
			(hide yes)
			(effects
				(font
					(size 1 1)
					(thickness 0.15)
				)
				(justify mirror)
			)
		)
		(property "Author" "Antmicro"
			(at 0 0 180)
			(unlocked yes)
			(layer "B.Fab")
			(hide yes)
			(effects
				(font
					(size 1 1)
					(thickness 0.15)
				)
				(justify mirror)
			)
		)
		(property "Tolerance" "1%"
			(at 0 0 180)
			(unlocked yes)
			(layer "B.Fab")
			(hide yes)
			(effects
				(font
					(size 1 1)
					(thickness 0.15)
				)
				(justify mirror)
			)
		)
		(sheetname "/HyperRAM + QSPI Flash/")
		(sheetfile "hyperram-flash.kicad_sch")
		(attr smd)
		(fp_rect
			(start -0.925 0.47)
			(end 0.925 -0.47)
			(stroke
				(width 0.05)
				(type default)
			)
			(fill no)
			(layer "B.CrtYd")
		)
		(fp_rect
			(start -0.5 0.25)
			(end 0.5 -0.25)
			(stroke
				(width 0.15)
				(type solid)
			)
			(fill no)
			(layer "B.Fab")
		)
		(fp_text user "${REFERENCE}"
			(at -0.95 -3.168 0)
			(layer "B.Fab")
			(effects
				(font
					(size 0.7 0.7)
					(thickness 0.15)
				)
				(justify left bottom mirror)
			)
		)
		(fp_text user "License: Apache-2.0"
			(at -0.95 -5.169 0)
			(layer "B.Fab")
			(effects
				(font
					(size 0.7 0.7)
					(thickness 0.15)
				)
				(justify left bottom mirror)
			)
		)
		(fp_text user "Author: Antmicro"
			(at -0.95 -4.169 0)
			(layer "B.Fab")
			(effects
				(font
					(size 0.7 0.7)
					(thickness 0.15)
				)
				(justify left bottom mirror)
			)
		)
		(pad "1" smd roundrect
			(at -0.48 0 180)
			(size 0.59 0.64)
			(layers "B.Cu" "B.Mask" "B.Paste")
			(roundrect_rratio 0.25)
			(net 797 "+1V8")
			(pintype "passive")
		)
		(pad "2" smd roundrect
			(at 0.48 0 180)
			(size 0.59 0.64)
			(layers "B.Cu" "B.Mask" "B.Paste")
			(roundrect_rratio 0.25)
			(net 279 "/HyperRAM + QSPI Flash/IO3")
			(pintype "passive")
		)
	)
	(footprint "antmicro-footprints:Coax_Conn_U.FL"
		(layer "B.Cu")
		(at 123.9 120.664 -90)
		(descr "https://media.digikey.com/pdf/Data%20Sheets/Hirose%20PDFs/UFL%20Series.pdf")
		(property "Reference" "J9"
			(at 3.036 -2.05 180)
			(layer "B.SilkS")
			(hide yes)
			(effects
				(font
					(size 0.7 0.7)
					(thickness 0.15)
				)
				(justify left bottom mirror)
			)
		)
		(property "Value" "U_FL-R-SMT-1"
			(at -4.13 -2.52 90)
			(layer "B.Fab")
			(effects
				(font
					(size 0.7 0.7)
					(thickness 0.15)
				)
				(justify left bottom mirror)
			)
		)
		(property "Datasheet" "https://media.digikey.com/pdf/Data%20Sheets/Hirose%20PDFs/UFL%20Series.pdf"
			(at 0 0 270)
			(layer "F.Fab")
			(hide yes)
			(effects
				(font
					(size 1.27 1.27)
					(thickness 0.15)
				)
			)
		)
		(property "MPN" "U.FL-R-SMT-1(10)"
			(at 0 0 270)
			(unlocked yes)
			(layer "B.Fab")
			(hide yes)
			(effects
				(font
					(size 1 1)
					(thickness 0.15)
				)
				(justify mirror)
			)
		)
		(property "Manufacturer" "Hirose Electric"
			(at 0 0 270)
			(unlocked yes)
			(layer "B.Fab")
			(hide yes)
			(effects
				(font
					(size 1 1)
					(thickness 0.15)
				)
				(justify mirror)
			)
		)
		(property "Author" "Antmicro"
			(at 0 0 270)
			(unlocked yes)
			(layer "B.Fab")
			(hide yes)
			(effects
				(font
					(size 1 1)
					(thickness 0.15)
				)
				(justify mirror)
			)
		)
		(property "License" "Apache-2.0"
			(at 0 0 270)
			(unlocked yes)
			(layer "B.Fab")
			(hide yes)
			(effects
				(font
					(size 1 1)
					(thickness 0.15)
				)
				(justify mirror)
			)
		)
		(sheetname "/Debug FTDI + VNA/")
		(sheetfile "debug-ftdi.kicad_sch")
		(attr smd)
		(fp_line
			(start -1.613 1.651)
			(end -1.113 1.651)
			(stroke
				(width 0.15)
				(type solid)
			)
			(layer "B.SilkS")
		)
		(fp_line
			(start -1.613 1.651)
			(end -1.613 1.325)
			(stroke
				(width 0.15)
				(type solid)
			)
			(layer "B.SilkS")
		)
		(fp_line
			(start 1.588 1.651)
			(end 1.088 1.651)
			(stroke
				(width 0.15)
				(type solid)
			)
			(layer "B.SilkS")
		)
		(fp_line
			(start 1.588 1.651)
			(end 1.588 1.325)
			(stroke
				(width 0.15)
				(type solid)
			)
			(layer "B.SilkS")
		)
		(fp_line
			(start -1.613 -1.648)
			(end -1.613 -1.325)
			(stroke
				(width 0.15)
				(type solid)
			)
			(layer "B.SilkS")
		)
		(fp_line
			(start -1.613 -1.648)
			(end -1.113 -1.648)
			(stroke
				(width 0.15)
				(type solid)
			)
			(layer "B.SilkS")
		)
		(fp_line
			(start 1.588 -1.648)
			(end 1.588 -1.325)
			(stroke
				(width 0.15)
				(type solid)
			)
			(layer "B.SilkS")
		)
		(fp_line
			(start 1.588 -1.648)
			(end 1.088 -1.648)
			(stroke
				(width 0.15)
				(type solid)
			)
			(layer "B.SilkS")
		)
		(fp_rect
			(start -2 2.051)
			(end 1.999 -2.05)
			(stroke
				(width 0.05)
				(type solid)
			)
			(fill no)
			(layer "B.CrtYd")
		)
		(fp_line
			(start -1.512 1.551)
			(end 1.487 1.551)
			(stroke
				(width 0.15)
				(type solid)
			)
			(layer "B.Fab")
		)
		(fp_line
			(start -1.512 -1.55)
			(end -1.512 1.551)
			(stroke
				(width 0.15)
				(type solid)
			)
			(layer "B.Fab")
		)
		(fp_line
			(start -1.512 -1.55)
			(end 1.487 -1.55)
			(stroke
				(width 0.15)
				(type solid)
			)
			(layer "B.Fab")
		)
		(fp_line
			(start 1.487 -1.55)
			(end 1.487 1.551)
			(stroke
				(width 0.15)
				(type solid)
			)
			(layer "B.Fab")
		)
		(fp_text user "${REFERENCE}"
			(at -4.13 -6.92 90)
			(layer "B.Fab")
			(effects
				(font
					(size 0.7 0.7)
					(thickness 0.15)
				)
				(justify left bottom mirror)
			)
		)
		(fp_text user "Author: Antmicro"
			(at -4.13 -4.52 90)
			(layer "B.Fab")
			(effects
				(font
					(size 0.7 0.7)
					(thickness 0.15)
				)
				(justify left bottom mirror)
			)
		)
		(fp_text user "License: Apache-2.0"
			(at -4.13 -5.72 90)
			(layer "B.Fab")
			(effects
				(font
					(size 0.7 0.7)
					(thickness 0.15)
				)
				(justify left bottom mirror)
			)
		)
		(pad "1" smd rect
			(at -0.012 -1.499 270)
			(size 1 1.05)
			(layers "B.Cu" "B.Mask" "B.Paste")
			(net 367 "unconnected-(J9-Pad1)")
			(pintype "passive+no_connect")
		)
		(pad "SH1" smd rect
			(at 1.463 0 270)
			(size 1.05 2.2)
			(layers "B.Cu" "B.Mask" "B.Paste")
			(net 1 "GND")
			(pintype "passive")
		)
		(pad "SH2" smd rect
			(at -1.488 0 270)
			(size 1.05 2.2)
			(layers "B.Cu" "B.Mask" "B.Paste")
			(net 1 "GND")
			(pintype "passive")
		)
		(zone
			(net 0)
			(net_name "")
			(layer "B.Cu")
			(hatch edge 0.508)
			(connect_pads
				(clearance 0)
			)
			(min_thickness 0.254)
			(filled_areas_thickness no)
			(keepout
				(tracks not_allowed)
				(vias not_allowed)
				(pads not_allowed)
				(copperpour not_allowed)
				(footprints not_allowed)
			)
			(placement
				(enabled no)
				(sheetname "")
			)
			(fill
				(thermal_gap 0.508)
				(thermal_bridge_width 0.508)
			)
			(polygon
				(pts
					(xy 124.86 121.594) (xy 124.86 119.714) (xy 122.8 119.714) (xy 122.8 121.594)
				)
			)
		)
	)
	(footprint "antmicro-footprints:C_0402_1005Metric"
		(layer "B.Cu")
		(at 207.94 150.97 90)
		(descr "Capacitor SMD 0402")
		(tags "capacitor SMD 0402")
		(property "Reference" "C204"
			(at 1.05 0.33 90)
			(layer "B.SilkS")
			(effects
				(font
					(size 0.7 0.7)
					(thickness 0.15)
				)
				(justify right bottom mirror)
			)
		)
		(property "Value" "C_1u_0402"
			(at -1.022927 -2.155213 90)
			(layer "B.Fab")
			(effects
				(font
					(size 0.7 0.7)
					(thickness 0.15)
				)
				(justify right bottom mirror)
			)
		)
		(property "Datasheet" "https://product.tdk.com/en/search/capacitor/ceramic/mlcc/info?part_no=C1005X6S1A105K050BC"
			(at 0 0 90)
			(layer "F.Fab")
			(hide yes)
			(effects
				(font
					(size 1.27 1.27)
					(thickness 0.15)
				)
			)
		)
		(property "MPN" "C1005X6S1A105K050BC"
			(at 0 0 90)
			(unlocked yes)
			(layer "B.Fab")
			(hide yes)
			(effects
				(font
					(size 1 1)
					(thickness 0.15)
				)
				(justify mirror)
			)
		)
		(property "Manufacturer" "TDK"
			(at 0 0 90)
			(unlocked yes)
			(layer "B.Fab")
			(hide yes)
			(effects
				(font
					(size 1 1)
					(thickness 0.15)
				)
				(justify mirror)
			)
		)
		(property "License" "Apache-2.0"
			(at 0 0 90)
			(unlocked yes)
			(layer "B.Fab")
			(hide yes)
			(effects
				(font
					(size 1 1)
					(thickness 0.15)
				)
				(justify mirror)
			)
		)
		(property "Author" "Antmicro"
			(at 0 0 90)
			(unlocked yes)
			(layer "B.Fab")
			(hide yes)
			(effects
				(font
					(size 1 1)
					(thickness 0.15)
				)
				(justify mirror)
			)
		)
		(property "Val" "1u"
			(at 0 0 90)
			(unlocked yes)
			(layer "B.Fab")
			(hide yes)
			(effects
				(font
					(size 1 1)
					(thickness 0.15)
				)
				(justify mirror)
			)
		)
		(property "Voltage" ""
			(at 0 0 90)
			(unlocked yes)
			(layer "B.Fab")
			(hide yes)
			(effects
				(font
					(size 1 1)
					(thickness 0.15)
				)
				(justify mirror)
			)
		)
		(property "Dielectric" ""
			(at 0 0 90)
			(unlocked yes)
			(layer "B.Fab")
			(hide yes)
			(effects
				(font
					(size 1 1)
					(thickness 0.15)
				)
				(justify mirror)
			)
		)
		(sheetname "/FPGA Config/")
		(sheetfile "fpga-config.kicad_sch")
		(attr smd)
		(fp_rect
			(start -0.925 0.47)
			(end 0.925 -0.47)
			(stroke
				(width 0.05)
				(type default)
			)
			(fill no)
			(layer "B.CrtYd")
		)
		(fp_line
			(start 0.504 -0.248)
			(end -0.494 -0.248)
			(stroke
				(width 0.15)
				(type solid)
			)
			(layer "B.Fab")
		)
		(fp_line
			(start -0.494 -0.248)
			(end -0.494 0.25)
			(stroke
				(width 0.15)
				(type solid)
			)
			(layer "B.Fab")
		)
		(fp_line
			(start 0.504 0.25)
			(end 0.504 -0.248)
			(stroke
				(width 0.15)
				(type solid)
			)
			(layer "B.Fab")
		)
		(fp_line
			(start -0.494 0.25)
			(end 0.504 0.25)
			(stroke
				(width 0.15)
				(type solid)
			)
			(layer "B.Fab")
		)
		(fp_text user "${REFERENCE}"
			(at -0.939 -4.599 270)
			(layer "B.Fab")
			(effects
				(font
					(size 0.7 0.7)
					(thickness 0.15)
				)
				(justify left bottom mirror)
			)
		)
		(fp_text user "Author: Antmicro"
			(at -0.939 -3.399 270)
			(layer "B.Fab")
			(effects
				(font
					(size 0.7 0.7)
					(thickness 0.15)
				)
				(justify left bottom mirror)
			)
		)
		(fp_text user "License: Apache-2.0"
			(at -0.939 -5.799 270)
			(layer "B.Fab")
			(effects
				(font
					(size 0.7 0.7)
					(thickness 0.15)
				)
				(justify left bottom mirror)
			)
		)
		(pad "1" smd roundrect
			(at -0.48 0 90)
			(size 0.59 0.64)
			(layers "B.Cu" "B.Mask" "B.Paste")
			(roundrect_rratio 0.25)
			(net 1 "GND")
			(pintype "passive")
		)
		(pad "2" smd roundrect
			(at 0.48 0 90)
			(size 0.59 0.64)
			(layers "B.Cu" "B.Mask" "B.Paste")
			(roundrect_rratio 0.25)
			(net 797 "+1V8")
			(pintype "passive")
		)
	)
	(footprint "antmicro-footprints:R_0402_1005Metric"
		(layer "B.Cu")
		(at 234.25 182.505 90)
		(descr "Resistor SMD 0402")
		(tags "resistor SMD 0402")
		(property "Reference" "R252"
			(at -1.285 0.6 90)
			(layer "B.SilkS")
			(effects
				(font
					(size 0.7 0.7)
					(thickness 0.15)
				)
				(justify right top mirror)
			)
		)
		(property "Value" "R_47k_0402"
			(at -1.011843 -1.772047 90)
			(layer "B.Fab")
			(effects
				(font
					(size 0.7 0.7)
					(thickness 0.15)
				)
				(justify right top mirror)
			)
		)
		(property "Datasheet" "https://www.bourns.com/docs/product-datasheets/cr.pdf"
			(at 0 0 90)
			(layer "B.Fab")
			(hide yes)
			(effects
				(font
					(size 1.27 1.27)
					(thickness 0.15)
				)
				(justify mirror)
			)
		)
		(property "MPN" "CR0402-FX-4702GLF"
			(at 0 0 90)
			(unlocked yes)
			(layer "B.Fab")
			(hide yes)
			(effects
				(font
					(size 1 1)
					(thickness 0.15)
				)
				(justify mirror)
			)
		)
		(property "Manufacturer" "Bourns"
			(at 0 0 90)
			(unlocked yes)
			(layer "B.Fab")
			(hide yes)
			(effects
				(font
					(size 1 1)
					(thickness 0.15)
				)
				(justify mirror)
			)
		)
		(property "License" "Apache-2.0"
			(at 0 0 90)
			(unlocked yes)
			(layer "B.Fab")
			(hide yes)
			(effects
				(font
					(size 1 1)
					(thickness 0.15)
				)
				(justify mirror)
			)
		)
		(property "Author" "Antmicro"
			(at 0 0 90)
			(unlocked yes)
			(layer "B.Fab")
			(hide yes)
			(effects
				(font
					(size 1 1)
					(thickness 0.15)
				)
				(justify mirror)
			)
		)
		(property "Val" "47k"
			(at 0 0 90)
			(unlocked yes)
			(layer "B.Fab")
			(hide yes)
			(effects
				(font
					(size 1 1)
					(thickness 0.15)
				)
				(justify mirror)
			)
		)
		(property "Tolerance" "1%"
			(at 0 0 90)
			(unlocked yes)
			(layer "B.Fab")
			(hide yes)
			(effects
				(font
					(size 1 1)
					(thickness 0.15)
				)
				(justify mirror)
			)
		)
		(sheetname "/Supply/DC-DC VCCINT/")
		(sheetfile "dc-dc-vccint.kicad_sch")
		(attr smd)
		(fp_rect
			(start -0.925 0.47)
			(end 0.925 -0.47)
			(stroke
				(width 0.05)
				(type default)
			)
			(fill no)
			(layer "B.CrtYd")
		)
		(fp_rect
			(start -0.5 0.25)
			(end 0.5 -0.25)
			(stroke
				(width 0.15)
				(type solid)
			)
			(fill no)
			(layer "B.Fab")
		)
		(fp_text user "License: Apache-2.0"
			(at -0.95 -5.169 270)
			(layer "B.Fab")
			(effects
				(font
					(size 0.7 0.7)
					(thickness 0.15)
				)
				(justify left bottom mirror)
			)
		)
		(fp_text user "${REFERENCE}"
			(at -0.95 -3.168 270)
			(layer "B.Fab")
			(effects
				(font
					(size 0.7 0.7)
					(thickness 0.15)
				)
				(justify left bottom mirror)
			)
		)
		(fp_text user "Author: Antmicro"
			(at -0.95 -4.169 270)
			(layer "B.Fab")
			(effects
				(font
					(size 0.7 0.7)
					(thickness 0.15)
				)
				(justify left bottom mirror)
			)
		)
		(pad "1" smd roundrect
			(at -0.48 0 90)
			(size 0.59 0.64)
			(layers "B.Cu" "B.Mask" "B.Paste")
			(roundrect_rratio 0.25)
			(net 777 "/Supply/DC-DC VCCINT/~{PS}")
			(pintype "passive")
		)
		(pad "2" smd roundrect
			(at 0.48 0 90)
			(size 0.59 0.64)
			(layers "B.Cu" "B.Mask" "B.Paste")
			(roundrect_rratio 0.25)
			(net 163 "/Supply/DC-DC VCCINT/V_{CC}")
			(pintype "passive")
		)
	)
)
